# T6G (Grand Teton) — schematic netlist excerpt (pin names and nets, part order shuffled) for the footprints in the layout excerpt that follows; sources: Cadence DE-HDL packaged netlist, KiCad conversion of 04192023_DAF0TMB3IC0_F0TG_MB_C_brd_V02_OCP.brd

R1642  Q_RES  22 1% CHIP  pkg 0402LF  page 173 : A = JTAG_P1_R_TCK ; B = JTAG_CPU1_TCK
PR3945  Q_RES  71.5K 1% CHIP  pkg 0402LF  page 147 : A = P3V3_E1S_MODE_0 ; B = GND

(kicad_pcb
	(version 20260206)
	(generator "pcbnew")
	(generator_version "10.0")
	(general
		(thickness 1.6)
		(legacy_teardrops no)
	)
	(paper "A4")
	(title_block
		(title "04192023_DAF0TMB3IC0_F0TG_MB_C_brd_V02_OCP.brd")
		(comment 1 "Grand Teton / footprints 277-278 of 8354")
	)
	(layers
		(0 "F.Cu" signal "TOP")
		(4 "In1.Cu" signal "GND")
		(6 "In2.Cu" signal "IN1")
		(8 "In3.Cu" signal "GND1")
		(10 "In4.Cu" signal "IN2")
		(12 "In5.Cu" signal "GND2")
		(14 "In6.Cu" signal "IN3")
		(16 "In7.Cu" signal "GND3")
		(18 "In8.Cu" signal "VCC")
		(20 "In9.Cu" signal "VCC1")
		(22 "In10.Cu" signal "GND4")
		(24 "In11.Cu" signal "IN4")
		(26 "In12.Cu" signal "GND5")
		(28 "In13.Cu" signal "IN5")
		(30 "In14.Cu" signal "GND6")
		(32 "In15.Cu" signal "IN6")
		(34 "In16.Cu" signal "GND7")
		(2 "B.Cu" signal "BOTTOM")
		(9 "F.Adhes" user "F.Adhesive")
		(11 "B.Adhes" user "B.Adhesive")
		(13 "F.Paste" user "Package Geometry/Pastemask Top")
		(15 "B.Paste" user "Package Geometry/Pastemask Bottom")
		(5 "F.SilkS" user "Ref Des/Silkscreen Top")
		(7 "B.SilkS" user "Ref Des/Silkscreen Bottom")
		(1 "F.Mask" user "Board Geometry/Soldermask Top")
		(3 "B.Mask" user "Board Geometry/Soldermask Bottom")
		(17 "Dwgs.User" user "User.Drawings")
		(19 "Cmts.User" user "User.Comments")
		(21 "Eco1.User" user "User.Eco1")
		(23 "Eco2.User" user "User.Eco2")
		(25 "Edge.Cuts" user "Board Geometry/Outline")
		(27 "Margin" user)
		(31 "F.CrtYd" user "Package Geometry/Place Bound Top")
		(29 "B.CrtYd" user "Package Geometry/Place Bound Bottom")
		(35 "F.Fab" user "Ref Des/Assembly Top")
		(33 "B.Fab" user "Ref Des/Assembly Bottom")
	)
	(footprint ""
		(layer "F.Cu")
		(at 275.14169 -96.323404 180)
		(property "Reference" "R1642"
			(at 0 0 180)
			(layer "F.SilkS")
			(hide yes)
			(effects
				(font
					(size 1.27 1.27)
				)
			)
		)
		(property "Value" ""
			(at 0 0 180)
			(layer "F.Fab")
			(effects
				(font
					(size 1.27 1.27)
				)
			)
		)
		(duplicate_pad_numbers_are_jumpers no)
		(fp_line
			(start 0.7874 0.4064)
			(end -0.7874 0.4064)
			(stroke
				(width 0.1524)
				(type default)
			)
			(layer "F.SilkS")
		)
		(fp_line
			(start 0.7874 -0.4064)
			(end 0.7874 0.4064)
			(stroke
				(width 0.1524)
				(type default)
			)
			(layer "F.SilkS")
		)
		(fp_line
			(start -0.7874 0.4064)
			(end -0.7874 -0.4064)
			(stroke
				(width 0.1524)
				(type default)
			)
			(layer "F.SilkS")
		)
		(fp_line
			(start -0.7874 -0.4064)
			(end 0.7874 -0.4064)
			(stroke
				(width 0.1524)
				(type default)
			)
			(layer "F.SilkS")
		)
		(fp_line
			(start 0.67945 0.3048)
			(end 0.120396 0.3048)
			(stroke
				(width 0.1)
				(type default)
			)
			(layer "F.Fab")
		)
		(fp_line
			(start 0.67945 -0.3048)
			(end 0.67945 0.3048)
			(stroke
				(width 0.1)
				(type default)
			)
			(layer "F.Fab")
		)
		(fp_line
			(start 0.12065 -0.2794)
			(end 0.12065 -0.3048)
			(stroke
				(width 0.1)
				(type default)
			)
			(layer "F.Fab")
		)
		(fp_line
			(start 0.12065 -0.3048)
			(end 0.67945 -0.3048)
			(stroke
				(width 0.1)
				(type default)
			)
			(layer "F.Fab")
		)
		(fp_line
			(start 0.120396 0.3048)
			(end 0.120396 0.2794)
			(stroke
				(width 0.1)
				(type default)
			)
			(layer "F.Fab")
		)
		(fp_line
			(start 0.120396 0.2794)
			(end -0.12065 0.2794)
			(stroke
				(width 0.1)
				(type default)
			)
			(layer "F.Fab")
		)
		(fp_line
			(start -0.12065 0.3048)
			(end -0.67945 0.3048)
			(stroke
				(width 0.1)
				(type default)
			)
			(layer "F.Fab")
		)
		(fp_line
			(start -0.12065 0.2794)
			(end -0.12065 0.3048)
			(stroke
				(width 0.1)
				(type default)
			)
			(layer "F.Fab")
		)
		(fp_line
			(start -0.12065 -0.2794)
			(end 0.12065 -0.2794)
			(stroke
				(width 0.1)
				(type default)
			)
			(layer "F.Fab")
		)
		(fp_line
			(start -0.12065 -0.305054)
			(end -0.12065 -0.2794)
			(stroke
				(width 0.1)
				(type default)
			)
			(layer "F.Fab")
		)
		(fp_line
			(start -0.67945 0.3048)
			(end -0.67945 -0.305054)
			(stroke
				(width 0.1)
				(type default)
			)
			(layer "F.Fab")
		)
		(fp_line
			(start -0.67945 -0.305054)
			(end -0.12065 -0.305054)
			(stroke
				(width 0.1)
				(type default)
			)
			(layer "F.Fab")
		)
		(pad "1" smd circle
			(at -0.40005 0 180)
			(size 0 0)
			(layers "F.Cu" "F.Mask" "F.Paste")
			(net "JTAG_P1_R_TCK")
		)
		(pad "2" smd circle
			(at 0.40005 0 180)
			(size 0 0)
			(layers "F.Cu" "F.Mask" "F.Paste")
			(net "JTAG_CPU1_TCK")
		)
	)
	(footprint ""
		(layer "F.Cu")
		(at 192.599564 -67.391788 180)
		(property "Reference" "PR3945"
			(at 0 0 180)
			(layer "F.SilkS")
			(hide yes)
			(effects
				(font
					(size 1.27 1.27)
				)
			)
		)
		(property "Value" ""
			(at 0 0 180)
			(layer "F.Fab")
			(effects
				(font
					(size 1.27 1.27)
				)
			)
		)
		(duplicate_pad_numbers_are_jumpers no)
		(fp_line
			(start 0.7874 0.4064)
			(end -0.7874 0.4064)
			(stroke
				(width 0.1524)
				(type default)
			)
			(layer "F.SilkS")
		)
		(fp_line
			(start 0.7874 -0.4064)
			(end 0.7874 0.4064)
			(stroke
				(width 0.1524)
				(type default)
			)
			(layer "F.SilkS")
		)
		(fp_line
			(start -0.7874 0.4064)
			(end -0.7874 -0.4064)
			(stroke
				(width 0.1524)
				(type default)
			)
			(layer "F.SilkS")
		)
		(fp_line
			(start -0.7874 -0.4064)
			(end 0.7874 -0.4064)
			(stroke
				(width 0.1524)
				(type default)
			)
			(layer "F.SilkS")
		)
		(fp_line
			(start 0.67945 0.3048)
			(end 0.120396 0.3048)
			(stroke
				(width 0.1)
				(type default)
			)
			(layer "F.Fab")
		)
		(fp_line
			(start 0.67945 -0.3048)
			(end 0.67945 0.3048)
			(stroke
				(width 0.1)
				(type default)
			)
			(layer "F.Fab")
		)
		(fp_line
			(start 0.12065 -0.2794)
			(end 0.12065 -0.3048)
			(stroke
				(width 0.1)
				(type default)
			)
			(layer "F.Fab")
		)
		(fp_line
			(start 0.12065 -0.3048)
			(end 0.67945 -0.3048)
			(stroke
				(width 0.1)
				(type default)
			)
			(layer "F.Fab")
		)
		(fp_line
			(start 0.120396 0.3048)
			(end 0.120396 0.2794)
			(stroke
				(width 0.1)
				(type default)
			)
			(layer "F.Fab")
		)
		(fp_line
			(start 0.120396 0.2794)
			(end -0.12065 0.2794)
			(stroke
				(width 0.1)
				(type default)
			)
			(layer "F.Fab")
		)
		(fp_line
			(start -0.12065 0.3048)
			(end -0.67945 0.3048)
			(stroke
				(width 0.1)
				(type default)
			)
			(layer "F.Fab")
		)
		(fp_line
			(start -0.12065 0.2794)
			(end -0.12065 0.3048)
			(stroke
				(width 0.1)
				(type default)
			)
			(layer "F.Fab")
		)
		(fp_line
			(start -0.12065 -0.2794)
			(end 0.12065 -0.2794)
			(stroke
				(width 0.1)
				(type default)
			)
			(layer "F.Fab")
		)
		(fp_line
			(start -0.12065 -0.305054)
			(end -0.12065 -0.2794)
			(stroke
				(width 0.1)
				(type default)
			)
			(layer "F.Fab")
		)
		(fp_line
			(start -0.67945 0.3048)
			(end -0.67945 -0.305054)
			(stroke
				(width 0.1)
				(type default)
			)
			(layer "F.Fab")
		)
		(fp_line
			(start -0.67945 -0.305054)
			(end -0.12065 -0.305054)
			(stroke
				(width 0.1)
				(type default)
			)
			(layer "F.Fab")
		)
		(pad "1" smd circle
			(at -0.40005 0 180)
			(size 0 0)
			(layers "F.Cu" "F.Mask" "F.Paste")
			(net "P3V3_E1S_MODE_0")
		)
		(pad "2" smd circle
			(at 0.40005 0 180)
			(size 0 0)
			(layers "F.Cu" "F.Mask" "F.Paste")
			(net "GND")
		)
	)
)
